(kicad_pcb
	(version 20260206)
	(generator "pcbnew")
	(generator_version "10.0")
	(general
		(thickness 1.6)
		(legacy_teardrops no)
	)
	(paper "A4")
	(title_block
		(title "03242023_DA0F0TMBIJ0_F0T_Motherboard_J_brd_V01_OCP.brd")
		(comment 1 "Grand Teton / footprints 4772-4777 of 6105")
	)
	(layers
		(0 "F.Cu" signal "TOP")
		(4 "In1.Cu" signal "GND")
		(6 "In2.Cu" signal "IN1")
		(8 "In3.Cu" signal "GND1")
		(10 "In4.Cu" signal "IN2")
		(12 "In5.Cu" signal "GND2")
		(14 "In6.Cu" signal "IN3")
		(16 "In7.Cu" signal "GND3")
		(18 "In8.Cu" signal "VCC")
		(20 "In9.Cu" signal "VCC1")
		(22 "In10.Cu" signal "GND4")
		(24 "In11.Cu" signal "IN4")
		(26 "In12.Cu" signal "GND5")
		(28 "In13.Cu" signal "IN5")
		(30 "In14.Cu" signal "GND6")
		(32 "In15.Cu" signal "IN6")
		(34 "In16.Cu" signal "GND7")
		(2 "B.Cu" signal "BOTTOM")
		(9 "F.Adhes" user "F.Adhesive")
		(11 "B.Adhes" user "B.Adhesive")
		(13 "F.Paste" user "Package Geometry/Pastemask Top")
		(15 "B.Paste" user "Package Geometry/Pastemask Bottom")
		(5 "F.SilkS" user "Ref Des/Silkscreen Top")
		(7 "B.SilkS" user "Ref Des/Silkscreen Bottom")
		(1 "F.Mask" user "Board Geometry/Soldermask Top")
		(3 "B.Mask" user "Board Geometry/Soldermask Bottom")
		(17 "Dwgs.User" user "User.Drawings")
		(19 "Cmts.User" user "User.Comments")
		(21 "Eco1.User" user "User.Eco1")
		(23 "Eco2.User" user "User.Eco2")
		(25 "Edge.Cuts" user "Board Geometry/Outline")
		(27 "Margin" user)
		(31 "F.CrtYd" user "Package Geometry/Place Bound Top")
		(29 "B.CrtYd" user "Package Geometry/Place Bound Bottom")
		(35 "F.Fab" user "Ref Des/Assembly Top")
		(33 "B.Fab" user "Ref Des/Assembly Bottom")
	)
	(footprint ""
		(layer "B.Cu")
		(at 197.19036 -124.170948 180)
		(property "Reference" "R1106"
			(at 0 0 0)
			(layer "B.SilkS")
			(hide yes)
			(effects
				(font
					(size 1.27 1.27)
				)
				(justify mirror)
			)
		)
		(property "Value" ""
			(at 0 0 0)
			(layer "B.Fab")
			(effects
				(font
					(size 1.27 1.27)
				)
				(justify mirror)
			)
		)
		(duplicate_pad_numbers_are_jumpers no)
		(fp_line
			(start 0.7874 0.4064)
			(end 0.7874 -0.4064)
			(stroke
				(width 0.1524)
				(type default)
			)
			(layer "B.SilkS")
		)
		(fp_line
			(start 0.7874 -0.4064)
			(end -0.7874 -0.4064)
			(stroke
				(width 0.1524)
				(type default)
			)
			(layer "B.SilkS")
		)
		(fp_line
			(start -0.7874 0.4064)
			(end 0.7874 0.4064)
			(stroke
				(width 0.1524)
				(type default)
			)
			(layer "B.SilkS")
		)
		(fp_line
			(start -0.7874 -0.4064)
			(end -0.7874 0.4064)
			(stroke
				(width 0.1524)
				(type default)
			)
			(layer "B.SilkS")
		)
		(fp_line
			(start 0.67945 0.3048)
			(end 0.67945 -0.305054)
			(stroke
				(width 0.1)
				(type default)
			)
			(layer "B.Fab")
		)
		(fp_line
			(start 0.67945 -0.305054)
			(end 0.12065 -0.305054)
			(stroke
				(width 0.1)
				(type default)
			)
			(layer "B.Fab")
		)
		(fp_line
			(start 0.12065 0.3048)
			(end 0.67945 0.3048)
			(stroke
				(width 0.1)
				(type default)
			)
			(layer "B.Fab")
		)
		(fp_line
			(start 0.12065 0.2794)
			(end 0.12065 0.3048)
			(stroke
				(width 0.1)
				(type default)
			)
			(layer "B.Fab")
		)
		(fp_line
			(start 0.12065 -0.2794)
			(end -0.12065 -0.2794)
			(stroke
				(width 0.1)
				(type default)
			)
			(layer "B.Fab")
		)
		(fp_line
			(start 0.12065 -0.305054)
			(end 0.12065 -0.2794)
			(stroke
				(width 0.1)
				(type default)
			)
			(layer "B.Fab")
		)
		(fp_line
			(start -0.120396 0.3048)
			(end -0.120396 0.2794)
			(stroke
				(width 0.1)
				(type default)
			)
			(layer "B.Fab")
		)
		(fp_line
			(start -0.120396 0.2794)
			(end 0.12065 0.2794)
			(stroke
				(width 0.1)
				(type default)
			)
			(layer "B.Fab")
		)
		(fp_line
			(start -0.12065 -0.2794)
			(end -0.12065 -0.3048)
			(stroke
				(width 0.1)
				(type default)
			)
			(layer "B.Fab")
		)
		(fp_line
			(start -0.12065 -0.3048)
			(end -0.67945 -0.3048)
			(stroke
				(width 0.1)
				(type default)
			)
			(layer "B.Fab")
		)
		(fp_line
			(start -0.67945 0.3048)
			(end -0.120396 0.3048)
			(stroke
				(width 0.1)
				(type default)
			)
			(layer "B.Fab")
		)
		(fp_line
			(start -0.67945 -0.3048)
			(end -0.67945 0.3048)
			(stroke
				(width 0.1)
				(type default)
			)
			(layer "B.Fab")
		)
		(pad "1" smd circle
			(at 0.40005 0)
			(size 0 0)
			(layers "B.Cu" "B.Mask" "B.Paste")
			(net "P3V3_AUX")
		)
		(pad "2" smd circle
			(at -0.40005 0)
			(size 0 0)
			(layers "B.Cu" "B.Mask" "B.Paste")
			(net "FM_PLD_REV_R_N")
		)
	)
	(footprint ""
		(layer "B.Cu")
		(at 386.960872 -346.805504 -90)
		(property "Reference" "PC236_P0_8"
			(at 0 0 90)
			(layer "B.SilkS")
			(hide yes)
			(effects
				(font
					(size 1.27 1.27)
				)
				(justify mirror)
			)
		)
		(property "Value" ""
			(at 0 0 90)
			(layer "B.Fab")
			(effects
				(font
					(size 1.27 1.27)
				)
				(justify mirror)
			)
		)
		(duplicate_pad_numbers_are_jumpers no)
		(fp_line
			(start -1.524 0.762)
			(end 1.524 0.762)
			(stroke
				(width 0.1524)
				(type default)
			)
			(layer "B.SilkS")
		)
		(fp_line
			(start 1.524 0.762)
			(end 1.524 -0.762)
			(stroke
				(width 0.1524)
				(type default)
			)
			(layer "B.SilkS")
		)
		(fp_line
			(start -1.524 -0.762)
			(end -1.524 0.762)
			(stroke
				(width 0.1524)
				(type default)
			)
			(layer "B.SilkS")
		)
		(fp_line
			(start 1.524 -0.762)
			(end -1.524 -0.762)
			(stroke
				(width 0.1524)
				(type default)
			)
			(layer "B.SilkS")
		)
		(fp_line
			(start -1.1049 0.724916)
			(end -1.1049 -0.724916)
			(stroke
				(width 0.1)
				(type default)
			)
			(layer "B.Fab")
		)
		(fp_line
			(start 1.1049 0.724916)
			(end -1.1049 0.724916)
			(stroke
				(width 0.1)
				(type default)
			)
			(layer "B.Fab")
		)
		(fp_line
			(start -1.1049 -0.724916)
			(end 1.1049 -0.724916)
			(stroke
				(width 0.1)
				(type default)
			)
			(layer "B.Fab")
		)
		(fp_line
			(start 1.1049 -0.724916)
			(end 1.1049 0.724916)
			(stroke
				(width 0.1)
				(type default)
			)
			(layer "B.Fab")
		)
		(pad "1" smd rect
			(at 0.889 0 270)
			(size 1.016 1.27)
			(layers "B.Cu" "B.Mask" "B.Paste")
			(net "SW_P12V_PVCCIN_CPU0_FLT")
		)
		(pad "2" smd rect
			(at -0.889 0 270)
			(size 1.016 1.27)
			(layers "B.Cu" "B.Mask" "B.Paste")
			(net "GND")
		)
	)
	(footprint ""
		(layer "B.Cu")
		(at 109.658912 -336.186018 -90)
		(property "Reference" "PR302"
			(at 0 0 90)
			(layer "B.SilkS")
			(hide yes)
			(effects
				(font
					(size 1.27 1.27)
				)
				(justify mirror)
			)
		)
		(property "Value" ""
			(at 0 0 90)
			(layer "B.Fab")
			(effects
				(font
					(size 1.27 1.27)
				)
				(justify mirror)
			)
		)
		(duplicate_pad_numbers_are_jumpers no)
		(fp_line
			(start -0.7874 0.4064)
			(end 0.7874 0.4064)
			(stroke
				(width 0.1524)
				(type default)
			)
			(layer "B.SilkS")
		)
		(fp_line
			(start 0.7874 0.4064)
			(end 0.7874 -0.4064)
			(stroke
				(width 0.1524)
				(type default)
			)
			(layer "B.SilkS")
		)
		(fp_line
			(start -0.7874 -0.4064)
			(end -0.7874 0.4064)
			(stroke
				(width 0.1524)
				(type default)
			)
			(layer "B.SilkS")
		)
		(fp_line
			(start 0.7874 -0.4064)
			(end -0.7874 -0.4064)
			(stroke
				(width 0.1524)
				(type default)
			)
			(layer "B.SilkS")
		)
		(fp_line
			(start -0.67945 0.3048)
			(end -0.120396 0.3048)
			(stroke
				(width 0.1)
				(type default)
			)
			(layer "B.Fab")
		)
		(fp_line
			(start -0.120396 0.3048)
			(end -0.120396 0.2794)
			(stroke
				(width 0.1)
				(type default)
			)
			(layer "B.Fab")
		)
		(fp_line
			(start 0.12065 0.3048)
			(end 0.67945 0.3048)
			(stroke
				(width 0.1)
				(type default)
			)
			(layer "B.Fab")
		)
		(fp_line
			(start 0.67945 0.3048)
			(end 0.67945 -0.305054)
			(stroke
				(width 0.1)
				(type default)
			)
			(layer "B.Fab")
		)
		(fp_line
			(start -0.120396 0.2794)
			(end 0.12065 0.2794)
			(stroke
				(width 0.1)
				(type default)
			)
			(layer "B.Fab")
		)
		(fp_line
			(start 0.12065 0.2794)
			(end 0.12065 0.3048)
			(stroke
				(width 0.1)
				(type default)
			)
			(layer "B.Fab")
		)
		(fp_line
			(start -0.12065 -0.2794)
			(end -0.12065 -0.3048)
			(stroke
				(width 0.1)
				(type default)
			)
			(layer "B.Fab")
		)
		(fp_line
			(start 0.12065 -0.2794)
			(end -0.12065 -0.2794)
			(stroke
				(width 0.1)
				(type default)
			)
			(layer "B.Fab")
		)
		(fp_line
			(start -0.67945 -0.3048)
			(end -0.67945 0.3048)
			(stroke
				(width 0.1)
				(type default)
			)
			(layer "B.Fab")
		)
		(fp_line
			(start -0.12065 -0.3048)
			(end -0.67945 -0.3048)
			(stroke
				(width 0.1)
				(type default)
			)
			(layer "B.Fab")
		)
		(fp_line
			(start 0.12065 -0.305054)
			(end 0.12065 -0.2794)
			(stroke
				(width 0.1)
				(type default)
			)
			(layer "B.Fab")
		)
		(fp_line
			(start 0.67945 -0.305054)
			(end 0.12065 -0.305054)
			(stroke
				(width 0.1)
				(type default)
			)
			(layer "B.Fab")
		)
		(pad "1" smd circle
			(at 0.40005 0 90)
			(size 0 0)
			(layers "B.Cu" "B.Mask" "B.Paste")
			(net "PVCCIN_CPU1_VOS3")
		)
		(pad "2" smd circle
			(at -0.40005 0 90)
			(size 0 0)
			(layers "B.Cu" "B.Mask" "B.Paste")
			(net "PVCCIN_CPU1")
		)
	)
	(footprint ""
		(layer "B.Cu")
		(at 54.880002 -168.370758 180)
		(property "Reference" "PC378"
			(at 0 0 0)
			(layer "B.SilkS")
			(hide yes)
			(effects
				(font
					(size 1.27 1.27)
				)
				(justify mirror)
			)
		)
		(property "Value" ""
			(at 0 0 0)
			(layer "B.Fab")
			(effects
				(font
					(size 1.27 1.27)
				)
				(justify mirror)
			)
		)
		(duplicate_pad_numbers_are_jumpers no)
		(fp_line
			(start 1.524 0.762)
			(end 1.524 -0.762)
			(stroke
				(width 0.1524)
				(type default)
			)
			(layer "B.SilkS")
		)
		(fp_line
			(start 1.524 -0.762)
			(end -1.524 -0.762)
			(stroke
				(width 0.1524)
				(type default)
			)
			(layer "B.SilkS")
		)
		(fp_line
			(start -1.524 0.762)
			(end 1.524 0.762)
			(stroke
				(width 0.1524)
				(type default)
			)
			(layer "B.SilkS")
		)
		(fp_line
			(start -1.524 -0.762)
			(end -1.524 0.762)
			(stroke
				(width 0.1524)
				(type default)
			)
			(layer "B.SilkS")
		)
		(fp_line
			(start 1.1049 0.724916)
			(end -1.1049 0.724916)
			(stroke
				(width 0.1)
				(type default)
			)
			(layer "B.Fab")
		)
		(fp_line
			(start 1.1049 -0.724916)
			(end 1.1049 0.724916)
			(stroke
				(width 0.1)
				(type default)
			)
			(layer "B.Fab")
		)
		(fp_line
			(start -1.1049 0.724916)
			(end -1.1049 -0.724916)
			(stroke
				(width 0.1)
				(type default)
			)
			(layer "B.Fab")
		)
		(fp_line
			(start -1.1049 -0.724916)
			(end 1.1049 -0.724916)
			(stroke
				(width 0.1)
				(type default)
			)
			(layer "B.Fab")
		)
		(pad "1" smd rect
			(at 0.889 0 180)
			(size 1.016 1.27)
			(layers "B.Cu" "B.Mask" "B.Paste")
			(net "SW_P12V_PVCCINFAON_CPU1_FLT")
		)
		(pad "2" smd rect
			(at -0.889 0 180)
			(size 1.016 1.27)
			(layers "B.Cu" "B.Mask" "B.Paste")
			(net "GND")
		)
	)
	(footprint ""
		(layer "B.Cu")
		(at 256.631948 -419.142672 90)
		(property "Reference" "PD15"
			(at 4.7244 -3.851148 90)
			(unlocked yes)
			(layer "B.SilkS")
			(effects
				(font
					(size 0.7874 0.5842)
					(thickness 0.1524)
				)
				(justify left mirror)
			)
		)
		(property "Value" ""
			(at 0 0 90)
			(layer "B.Fab")
			(effects
				(font
					(size 1.27 1.27)
				)
				(justify mirror)
			)
		)
		(duplicate_pad_numbers_are_jumpers no)
		(fp_line
			(start 4.664456 -3.109976)
			(end -4.743704 -3.109976)
			(stroke
				(width 0.1524)
				(type default)
			)
			(layer "B.SilkS")
		)
		(fp_line
			(start -4.183126 -3.109976)
			(end -4.794504 -3.109976)
			(stroke
				(width 0.1524)
				(type default)
			)
			(layer "B.SilkS")
		)
		(fp_line
			(start -4.511802 -3.109976)
			(end -4.207002 -3.109976)
			(stroke
				(width 0.1524)
				(type default)
			)
			(layer "B.SilkS")
		)
		(fp_line
			(start -4.6101 -3.109976)
			(end -4.283202 -3.109976)
			(stroke
				(width 0.1524)
				(type default)
			)
			(layer "B.SilkS")
		)
		(fp_line
			(start -4.695444 -3.109976)
			(end -4.695444 3.109976)
			(stroke
				(width 0.1524)
				(type default)
			)
			(layer "B.SilkS")
		)
		(fp_line
			(start -4.70535 -3.109976)
			(end -4.70535 3.109976)
			(stroke
				(width 0.1524)
				(type default)
			)
			(layer "B.SilkS")
		)
		(fp_line
			(start -4.70535 -3.109976)
			(end -4.70535 3.109976)
			(stroke
				(width 0.1524)
				(type default)
			)
			(layer "B.SilkS")
		)
		(fp_line
			(start -4.70535 -3.109976)
			(end -4.70535 3.109976)
			(stroke
				(width 0.1524)
				(type default)
			)
			(layer "B.SilkS")
		)
		(fp_line
			(start -4.805426 -3.109976)
			(end -4.805426 3.109976)
			(stroke
				(width 0.1524)
				(type default)
			)
			(layer "B.SilkS")
		)
		(fp_line
			(start -4.932426 -3.109976)
			(end -4.932426 3.109976)
			(stroke
				(width 0.1524)
				(type default)
			)
			(layer "B.SilkS")
		)
		(fp_line
			(start -5.008626 -3.109976)
			(end -5.008626 3.109976)
			(stroke
				(width 0.1524)
				(type default)
			)
			(layer "B.SilkS")
		)
		(fp_line
			(start -5.110226 -3.109976)
			(end -5.110226 3.109976)
			(stroke
				(width 0.1524)
				(type default)
			)
			(layer "B.SilkS")
		)
		(fp_line
			(start -5.211826 -3.109976)
			(end -5.211826 3.109976)
			(stroke
				(width 0.1524)
				(type default)
			)
			(layer "B.SilkS")
		)
		(fp_line
			(start -5.262626 -3.109976)
			(end -5.262626 3.109976)
			(stroke
				(width 0.1524)
				(type default)
			)
			(layer "B.SilkS")
		)
		(fp_line
			(start -5.313426 -3.109976)
			(end -5.313426 3.109976)
			(stroke
				(width 0.1524)
				(type default)
			)
			(layer "B.SilkS")
		)
		(fp_line
			(start -5.4102 -3.109976)
			(end -4.783074 -3.109976)
			(stroke
				(width 0.1524)
				(type default)
			)
			(layer "B.SilkS")
		)
		(fp_line
			(start 0.508 -1.016)
			(end -0.762 0)
			(stroke
				(width 0.1524)
				(type default)
			)
			(layer "B.SilkS")
		)
		(fp_line
			(start 1.0668 0)
			(end 0.6096 0)
			(stroke
				(width 0.1524)
				(type default)
			)
			(layer "B.SilkS")
		)
		(fp_line
			(start -0.762 0)
			(end -1.2192 0)
			(stroke
				(width 0.1524)
				(type default)
			)
			(layer "B.SilkS")
		)
		(fp_line
			(start -0.762 0)
			(end 0.508 1.016)
			(stroke
				(width 0.1524)
				(type default)
			)
			(layer "B.SilkS")
		)
		(fp_line
			(start 0.508 1.016)
			(end 0.508 -1.016)
			(stroke
				(width 0.1524)
				(type default)
			)
			(layer "B.SilkS")
		)
		(fp_line
			(start -0.762 1.27)
			(end -0.762 -1.27)
			(stroke
				(width 0.1524)
				(type default)
			)
			(layer "B.SilkS")
		)
		(fp_line
			(start -4.715002 3.035554)
			(end -4.7117 2.984754)
			(stroke
				(width 0.1524)
				(type default)
			)
			(layer "B.SilkS")
		)
		(fp_line
			(start 4.664456 3.109976)
			(end 4.664456 -3.109976)
			(stroke
				(width 0.1524)
				(type default)
			)
			(layer "B.SilkS")
		)
		(fp_line
			(start -4.156202 3.109976)
			(end -4.183126 3.109976)
			(stroke
				(width 0.1524)
				(type default)
			)
			(layer "B.SilkS")
		)
		(fp_line
			(start -4.743704 3.109976)
			(end -4.6101 3.109976)
			(stroke
				(width 0.1524)
				(type default)
			)
			(layer "B.SilkS")
		)
		(fp_line
			(start -4.743704 3.109976)
			(end -5.4102 3.109976)
			(stroke
				(width 0.1524)
				(type default)
			)
			(layer "B.SilkS")
		)
		(fp_line
			(start -4.769104 3.109976)
			(end 4.664456 3.109976)
			(stroke
				(width 0.1524)
				(type default)
			)
			(layer "B.SilkS")
		)
		(fp_line
			(start -4.794504 3.109976)
			(end -3.554984 3.109976)
			(stroke
				(width 0.1524)
				(type default)
			)
			(layer "B.SilkS")
		)
		(fp_line
			(start -5.4102 3.109976)
			(end -5.4102 -3.109976)
			(stroke
				(width 0.1524)
				(type default)
			)
			(layer "B.SilkS")
		)
		(fp_line
			(start 4.065016 -3.109976)
			(end -4.065016 -3.109976)
			(stroke
				(width 0.1)
				(type default)
			)
			(layer "B.Fab")
		)
		(fp_line
			(start -4.065016 -3.109976)
			(end -4.065016 3.109976)
			(stroke
				(width 0.1)
				(type default)
			)
			(layer "B.Fab")
		)
		(fp_line
			(start 4.065016 3.109976)
			(end 4.065016 -3.109976)
			(stroke
				(width 0.1)
				(type default)
			)
			(layer "B.Fab")
		)
		(fp_line
			(start -4.065016 3.109976)
			(end 4.065016 3.109976)
			(stroke
				(width 0.1)
				(type default)
			)
			(layer "B.Fab")
		)
		(fp_text user "+"
			(at 4.5974 0.24765 270)
			(unlocked yes)
			(layer "B.SilkS")
			(effects
				(font
					(size 1.905 1.4224)
					(thickness 0.1524)
				)
				(justify left mirror)
			)
		)
		(fp_text user "-"
			(at -6.643624 0.40005 270)
			(unlocked yes)
			(layer "B.SilkS")
			(effects
				(font
					(size 1.905 1.4224)
					(thickness 0.1524)
				)
				(justify left mirror)
			)
		)
		(fp_text user "+"
			(at 4.5974 0.24765 270)
			(unlocked yes)
			(layer "B.Fab")
			(effects
				(font
					(size 1.905 1.4224)
					(thickness 0.1524)
				)
				(justify left mirror)
			)
		)
		(fp_text user "-"
			(at -6.643624 0.40005 270)
			(unlocked yes)
			(layer "B.Fab")
			(effects
				(font
					(size 1.905 1.4224)
					(thickness 0.1524)
				)
				(justify left mirror)
			)
		)
		(pad "A" smd rect
			(at 3.299968 0 90)
			(size 2.413 3.302)
			(layers "B.Cu" "B.Mask" "B.Paste")
			(net "GND")
		)
		(pad "C" smd rect
			(at -3.299968 0 90)
			(size 2.413 3.302)
			(layers "B.Cu" "B.Mask" "B.Paste")
			(net "P12V_PSU_FUSE")
		)
	)
	(footprint ""
		(layer "B.Cu")
		(at 203.072746 -75.053952)
		(property "Reference" "R3210"
			(at 0 0 0)
			(layer "B.SilkS")
			(hide yes)
			(effects
				(font
					(size 1.27 1.27)
				)
				(justify mirror)
			)
		)
		(property "Value" ""
			(at 0 0 0)
			(layer "B.Fab")
			(effects
				(font
					(size 1.27 1.27)
				)
				(justify mirror)
			)
		)
		(duplicate_pad_numbers_are_jumpers no)
		(fp_line
			(start -0.7874 -0.4064)
			(end -0.7874 0.4064)
			(stroke
				(width 0.1524)
				(type default)
			)
			(layer "B.SilkS")
		)
		(fp_line
			(start -0.7874 0.4064)
			(end 0.7874 0.4064)
			(stroke
				(width 0.1524)
				(type default)
			)
			(layer "B.SilkS")
		)
		(fp_line
			(start 0.7874 -0.4064)
			(end -0.7874 -0.4064)
			(stroke
				(width 0.1524)
				(type default)
			)
			(layer "B.SilkS")
		)
		(fp_line
			(start 0.7874 0.4064)
			(end 0.7874 -0.4064)
			(stroke
				(width 0.1524)
				(type default)
			)
			(layer "B.SilkS")
		)
		(fp_line
			(start -0.67945 -0.3048)
			(end -0.67945 0.3048)
			(stroke
				(width 0.1)
				(type default)
			)
			(layer "B.Fab")
		)
		(fp_line
			(start -0.67945 0.3048)
			(end -0.120396 0.3048)
			(stroke
				(width 0.1)
				(type default)
			)
			(layer "B.Fab")
		)
		(fp_line
			(start -0.12065 -0.3048)
			(end -0.67945 -0.3048)
			(stroke
				(width 0.1)
				(type default)
			)
			(layer "B.Fab")
		)
		(fp_line
			(start -0.12065 -0.2794)
			(end -0.12065 -0.3048)
			(stroke
				(width 0.1)
				(type default)
			)
			(layer "B.Fab")
		)
		(fp_line
			(start -0.120396 0.2794)
			(end 0.12065 0.2794)
			(stroke
				(width 0.1)
				(type default)
			)
			(layer "B.Fab")
		)
		(fp_line
			(start -0.120396 0.3048)
			(end -0.120396 0.2794)
			(stroke
				(width 0.1)
				(type default)
			)
			(layer "B.Fab")
		)
		(fp_line
			(start 0.12065 -0.305054)
			(end 0.12065 -0.2794)
			(stroke
				(width 0.1)
				(type default)
			)
			(layer "B.Fab")
		)
		(fp_line
			(start 0.12065 -0.2794)
			(end -0.12065 -0.2794)
			(stroke
				(width 0.1)
				(type default)
			)
			(layer "B.Fab")
		)
		(fp_line
			(start 0.12065 0.2794)
			(end 0.12065 0.3048)
			(stroke
				(width 0.1)
				(type default)
			)
			(layer "B.Fab")
		)
		(fp_line
			(start 0.12065 0.3048)
			(end 0.67945 0.3048)
			(stroke
				(width 0.1)
				(type default)
			)
			(layer "B.Fab")
		)
		(fp_line
			(start 0.67945 -0.305054)
			(end 0.12065 -0.305054)
			(stroke
				(width 0.1)
				(type default)
			)
			(layer "B.Fab")
		)
		(fp_line
			(start 0.67945 0.3048)
			(end 0.67945 -0.305054)
			(stroke
				(width 0.1)
				(type default)
			)
			(layer "B.Fab")
		)
		(pad "1" smd circle
			(at 0.40005 0 180)
			(size 0 0)
			(layers "B.Cu" "B.Mask" "B.Paste")
			(net "NCSI_BMC_CRS_DV_R1")
		)
		(pad "2" smd circle
			(at -0.40005 0 180)
			(size 0 0)
			(layers "B.Cu" "B.Mask" "B.Paste")
			(net "RMII_OCP_BMC_CRSDV")
		)
	)
)
